# S9S_MB_2U (Grand Teton) — schematic netlist excerpt (pin names and nets, part order shuffled) for the footprints in the layout excerpt that follows; sources: Cadence DE-HDL packaged netlist, KiCad conversion of 03242023_DA0F0TMBIJ0_F0T_Motherboard_J_brd_V01_OCP.brd

C1150  Q_CAP  0.1UF 25V 10% X7R  pkg 0402  page 217 : A = VCC_PLD_CORE ; B = GND
R288  Q_RES  240 1% EMPTY  pkg 0402LF  page 119 : A = PVNN_TERM_CPU0 ; B = PD_CPU1_TXT_PLTEN
C322  Q_CAP  47UF 4V 20% X6S  pkg C0805  page 79 : A = PVCCIN_CPU1 ; B = GND

(kicad_pcb
	(version 20260206)
	(generator "pcbnew")
	(generator_version "10.0")
	(general
		(thickness 1.6)
		(legacy_teardrops no)
	)
	(paper "A4")
	(title_block
		(title "03242023_DA0F0TMBIJ0_F0T_Motherboard_J_brd_V01_OCP.brd")
		(comment 1 "Grand Teton / footprints 5897-5899 of 6105")
	)
	(layers
		(0 "F.Cu" signal "TOP")
		(4 "In1.Cu" signal "GND")
		(6 "In2.Cu" signal "IN1")
		(8 "In3.Cu" signal "GND1")
		(10 "In4.Cu" signal "IN2")
		(12 "In5.Cu" signal "GND2")
		(14 "In6.Cu" signal "IN3")
		(16 "In7.Cu" signal "GND3")
		(18 "In8.Cu" signal "VCC")
		(20 "In9.Cu" signal "VCC1")
		(22 "In10.Cu" signal "GND4")
		(24 "In11.Cu" signal "IN4")
		(26 "In12.Cu" signal "GND5")
		(28 "In13.Cu" signal "IN5")
		(30 "In14.Cu" signal "GND6")
		(32 "In15.Cu" signal "IN6")
		(34 "In16.Cu" signal "GND7")
		(2 "B.Cu" signal "BOTTOM")
		(9 "F.Adhes" user "F.Adhesive")
		(11 "B.Adhes" user "B.Adhesive")
		(13 "F.Paste" user "Package Geometry/Pastemask Top")
		(15 "B.Paste" user "Package Geometry/Pastemask Bottom")
		(5 "F.SilkS" user "Ref Des/Silkscreen Top")
		(7 "B.SilkS" user "Ref Des/Silkscreen Bottom")
		(1 "F.Mask" user "Board Geometry/Soldermask Top")
		(3 "B.Mask" user "Board Geometry/Soldermask Bottom")
		(17 "Dwgs.User" user "User.Drawings")
		(19 "Cmts.User" user "User.Comments")
		(21 "Eco1.User" user "User.Eco1")
		(23 "Eco2.User" user "User.Eco2")
		(25 "Edge.Cuts" user "Board Geometry/Outline")
		(27 "Margin" user)
		(31 "F.CrtYd" user "Package Geometry/Place Bound Top")
		(29 "B.CrtYd" user "Package Geometry/Place Bound Bottom")
		(35 "F.Fab" user "Ref Des/Assembly Top")
		(33 "B.Fab" user "Ref Des/Assembly Bottom")
	)
	(footprint ""
		(layer "B.Cu")
		(at 176.955704 -113.77549)
		(property "Reference" "C1150"
			(at 0 0 0)
			(layer "B.SilkS")
			(hide yes)
			(effects
				(font
					(size 1.27 1.27)
				)
				(justify mirror)
			)
		)
		(property "Value" ""
			(at 0 0 0)
			(layer "B.Fab")
			(effects
				(font
					(size 1.27 1.27)
				)
				(justify mirror)
			)
		)
		(duplicate_pad_numbers_are_jumpers no)
		(fp_line
			(start -0.69215 -0.2921)
			(end -0.69215 0.2921)
			(stroke
				(width 0.1524)
				(type default)
			)
			(layer "B.SilkS")
		)
		(fp_line
			(start -0.69215 0.2921)
			(end 0.69215 0.2921)
			(stroke
				(width 0.1524)
				(type default)
			)
			(layer "B.SilkS")
		)
		(fp_line
			(start 0.69215 -0.2921)
			(end -0.69215 -0.2921)
			(stroke
				(width 0.1524)
				(type default)
			)
			(layer "B.SilkS")
		)
		(fp_line
			(start 0.69215 0.2921)
			(end 0.69215 -0.2921)
			(stroke
				(width 0.1524)
				(type default)
			)
			(layer "B.SilkS")
		)
		(fp_line
			(start -0.51435 -0.2794)
			(end -0.51435 0.2794)
			(stroke
				(width 0.1)
				(type default)
			)
			(layer "B.Fab")
		)
		(fp_line
			(start -0.51435 0.2794)
			(end 0.51435 0.2794)
			(stroke
				(width 0.1)
				(type default)
			)
			(layer "B.Fab")
		)
		(fp_line
			(start 0.51435 -0.2794)
			(end -0.51435 -0.2794)
			(stroke
				(width 0.1)
				(type default)
			)
			(layer "B.Fab")
		)
		(fp_line
			(start 0.51435 0.2794)
			(end 0.51435 -0.2794)
			(stroke
				(width 0.1)
				(type default)
			)
			(layer "B.Fab")
		)
		(pad "1" smd circle
			(at 0.40005 0 180)
			(size 0 0)
			(layers "B.Cu" "B.Mask" "B.Paste")
			(net "VCC_PLD_CORE")
		)
		(pad "2" smd circle
			(at -0.40005 0 180)
			(size 0 0)
			(layers "B.Cu" "B.Mask" "B.Paste")
			(net "GND")
		)
		(zone
			(layer "B.Cu")
			(hatch none 0.5)
			(connect_pads
				(clearance 0)
			)
			(min_thickness 0.25)
			(keepout
				(tracks not_allowed)
				(vias allowed)
				(pads allowed)
				(copperpour not_allowed)
				(footprints allowed)
			)
			(placement
				(enabled no)
				(sheetname "")
			)
			(fill
				(thermal_gap 0.5)
				(thermal_bridge_width 0.5)
				(island_removal_mode 0)
			)
			(polygon
				(pts
					(xy 177.146204 -113.68786) (xy 177.054764 -113.629694) (xy 176.855374 -113.629694) (xy 176.765204 -113.68786)
					(xy 176.765204 -113.86312) (xy 176.855374 -113.92154) (xy 177.054764 -113.92154) (xy 177.146204 -113.863374)
				)
			)
		)
	)
	(footprint ""
		(layer "B.Cu")
		(at 151.059388 -188.20257)
		(property "Reference" "R288"
			(at 0 0 0)
			(layer "B.SilkS")
			(hide yes)
			(effects
				(font
					(size 1.27 1.27)
				)
				(justify mirror)
			)
		)
		(property "Value" ""
			(at 0 0 0)
			(layer "B.Fab")
			(effects
				(font
					(size 1.27 1.27)
				)
				(justify mirror)
			)
		)
		(duplicate_pad_numbers_are_jumpers no)
		(fp_line
			(start -0.7874 -0.4064)
			(end -0.7874 0.4064)
			(stroke
				(width 0.1524)
				(type default)
			)
			(layer "B.SilkS")
		)
		(fp_line
			(start -0.7874 0.4064)
			(end 0.7874 0.4064)
			(stroke
				(width 0.1524)
				(type default)
			)
			(layer "B.SilkS")
		)
		(fp_line
			(start 0.7874 -0.4064)
			(end -0.7874 -0.4064)
			(stroke
				(width 0.1524)
				(type default)
			)
			(layer "B.SilkS")
		)
		(fp_line
			(start 0.7874 0.4064)
			(end 0.7874 -0.4064)
			(stroke
				(width 0.1524)
				(type default)
			)
			(layer "B.SilkS")
		)
		(fp_line
			(start -0.67945 -0.3048)
			(end -0.67945 0.3048)
			(stroke
				(width 0.1)
				(type default)
			)
			(layer "B.Fab")
		)
		(fp_line
			(start -0.67945 0.3048)
			(end -0.120396 0.3048)
			(stroke
				(width 0.1)
				(type default)
			)
			(layer "B.Fab")
		)
		(fp_line
			(start -0.12065 -0.3048)
			(end -0.67945 -0.3048)
			(stroke
				(width 0.1)
				(type default)
			)
			(layer "B.Fab")
		)
		(fp_line
			(start -0.12065 -0.2794)
			(end -0.12065 -0.3048)
			(stroke
				(width 0.1)
				(type default)
			)
			(layer "B.Fab")
		)
		(fp_line
			(start -0.120396 0.2794)
			(end 0.12065 0.2794)
			(stroke
				(width 0.1)
				(type default)
			)
			(layer "B.Fab")
		)
		(fp_line
			(start -0.120396 0.3048)
			(end -0.120396 0.2794)
			(stroke
				(width 0.1)
				(type default)
			)
			(layer "B.Fab")
		)
		(fp_line
			(start 0.12065 -0.305054)
			(end 0.12065 -0.2794)
			(stroke
				(width 0.1)
				(type default)
			)
			(layer "B.Fab")
		)
		(fp_line
			(start 0.12065 -0.2794)
			(end -0.12065 -0.2794)
			(stroke
				(width 0.1)
				(type default)
			)
			(layer "B.Fab")
		)
		(fp_line
			(start 0.12065 0.2794)
			(end 0.12065 0.3048)
			(stroke
				(width 0.1)
				(type default)
			)
			(layer "B.Fab")
		)
		(fp_line
			(start 0.12065 0.3048)
			(end 0.67945 0.3048)
			(stroke
				(width 0.1)
				(type default)
			)
			(layer "B.Fab")
		)
		(fp_line
			(start 0.67945 -0.305054)
			(end 0.12065 -0.305054)
			(stroke
				(width 0.1)
				(type default)
			)
			(layer "B.Fab")
		)
		(fp_line
			(start 0.67945 0.3048)
			(end 0.67945 -0.305054)
			(stroke
				(width 0.1)
				(type default)
			)
			(layer "B.Fab")
		)
		(pad "1" smd circle
			(at 0.40005 0 180)
			(size 0 0)
			(layers "B.Cu" "B.Mask" "B.Paste")
			(net "PVNN_TERM_CPU0")
		)
		(pad "2" smd circle
			(at -0.40005 0 180)
			(size 0 0)
			(layers "B.Cu" "B.Mask" "B.Paste")
			(net "PD_CPU1_TXT_PLTEN")
		)
	)
	(footprint ""
		(layer "B.Cu")
		(at 102.495604 -294.01008 180)
		(property "Reference" "C322"
			(at 0 0 0)
			(layer "B.SilkS")
			(hide yes)
			(effects
				(font
					(size 1.27 1.27)
				)
				(justify mirror)
			)
		)
		(property "Value" ""
			(at 0 0 0)
			(layer "B.Fab")
			(effects
				(font
					(size 1.27 1.27)
				)
				(justify mirror)
			)
		)
		(duplicate_pad_numbers_are_jumpers no)
		(fp_line
			(start 1.524 0.762)
			(end 1.524 -0.762)
			(stroke
				(width 0.1524)
				(type default)
			)
			(layer "B.SilkS")
		)
		(fp_line
			(start 1.524 -0.762)
			(end -1.524 -0.762)
			(stroke
				(width 0.1524)
				(type default)
			)
			(layer "B.SilkS")
		)
		(fp_line
			(start -1.524 0.762)
			(end 1.524 0.762)
			(stroke
				(width 0.1524)
				(type default)
			)
			(layer "B.SilkS")
		)
		(fp_line
			(start -1.524 -0.762)
			(end -1.524 0.762)
			(stroke
				(width 0.1524)
				(type default)
			)
			(layer "B.SilkS")
		)
		(fp_line
			(start 1.1049 0.724916)
			(end -1.1049 0.724916)
			(stroke
				(width 0.1)
				(type default)
			)
			(layer "B.Fab")
		)
		(fp_line
			(start 1.1049 -0.724916)
			(end 1.1049 0.724916)
			(stroke
				(width 0.1)
				(type default)
			)
			(layer "B.Fab")
		)
		(fp_line
			(start -1.1049 0.724916)
			(end -1.1049 -0.724916)
			(stroke
				(width 0.1)
				(type default)
			)
			(layer "B.Fab")
		)
		(fp_line
			(start -1.1049 -0.724916)
			(end 1.1049 -0.724916)
			(stroke
				(width 0.1)
				(type default)
			)
			(layer "B.Fab")
		)
		(pad "1" smd rect
			(at 0.889 0 180)
			(size 1.016 1.27)
			(layers "B.Cu" "B.Mask" "B.Paste")
			(net "PVCCIN_CPU1")
		)
		(pad "2" smd rect
			(at -0.889 0 180)
			(size 1.016 1.27)
			(layers "B.Cu" "B.Mask" "B.Paste")
			(net "GND")
		)
	)
)
